(kicad_pcb
	(version 20241229)
	(generator "pcbnew")
	(generator_version "9.0")
	(general
		(thickness 1.711)
		(legacy_teardrops no)
	)
	(paper "A4")
	(title_block
		(title "Antmicro Baseboard for Jetson AGX Thor")
		(date "2026-02-18")
		(rev "1.1.0")
		(company "Antmicro Ltd")
		(comment 1 "www.antmicro.com")
		(comment 9 "footprints 1022-1026 of 1170")
	)
	(layers
		(0 "F.Cu" signal)
		(4 "In1.Cu" signal)
		(6 "In2.Cu" signal)
		(8 "In3.Cu" signal)
		(10 "In4.Cu" jumper)
		(12 "In5.Cu" signal)
		(14 "In6.Cu" signal)
		(16 "In7.Cu" signal)
		(18 "In8.Cu" signal)
		(2 "B.Cu" signal)
		(9 "F.Adhes" user "F.Adhesive")
		(11 "B.Adhes" user "B.Adhesive")
		(13 "F.Paste" user)
		(15 "B.Paste" user)
		(5 "F.SilkS" user "F.Silkscreen")
		(7 "B.SilkS" user "B.Silkscreen")
		(1 "F.Mask" user)
		(3 "B.Mask" user)
		(17 "Dwgs.User" user "User.Drawings")
		(19 "Cmts.User" user "User.Comments")
		(21 "Eco1.User" user "User.Eco1")
		(23 "Eco2.User" user "User.Eco2")
		(25 "Edge.Cuts" user)
		(27 "Margin" user)
		(31 "F.CrtYd" user "F.Courtyard")
		(29 "B.CrtYd" user "B.Courtyard")
		(35 "F.Fab" user)
		(33 "B.Fab" user)
	)
	(footprint "antmicro-footprints:R_0402_1005Metric"
		(layer "B.Cu")
		(at 198.6 70.6 -90)
		(descr "Resistor SMD 0402")
		(tags "resistor SMD 0402")
		(property "Reference" "R103"
			(at -1.2 -3.5 90)
			(layer "B.SilkS")
			(effects
				(font
					(size 0.7 0.7)
					(thickness 0.15)
				)
				(justify left bottom mirror)
			)
		)
		(property "Value" "R_4k7_0402"
			(at -1.011843 -1.772046 90)
			(layer "B.Fab")
			(effects
				(font
					(size 0.7 0.7)
					(thickness 0.15)
				)
				(justify left bottom mirror)
			)
		)
		(property "Datasheet" "https://www.bourns.com/docs/product-datasheets/cr.pdf"
			(at 0 0 90)
			(layer "B.Fab")
			(hide yes)
			(effects
				(font
					(size 1.27 1.27)
					(thickness 0.15)
				)
				(justify mirror)
			)
		)
		(property "Description" "SMD Chip Resistor, 4.7 kohm, ± 1%, 62.5 mW, 0402 [1005 Metric], Thick Film, General Purpose"
			(at 0 0 90)
			(layer "B.Fab")
			(hide yes)
			(effects
				(font
					(size 1.27 1.27)
					(thickness 0.15)
				)
				(justify mirror)
			)
		)
		(property "Manufacturer" "Bourns"
			(at 0 0 90)
			(unlocked yes)
			(layer "B.Fab")
			(hide yes)
			(effects
				(font
					(size 1 1)
					(thickness 0.15)
				)
				(justify mirror)
			)
		)
		(property "MPN" "CR0402-FX-4701GLF"
			(at 0 0 90)
			(unlocked yes)
			(layer "B.Fab")
			(hide yes)
			(effects
				(font
					(size 1 1)
					(thickness 0.15)
				)
				(justify mirror)
			)
		)
		(property "Val" "4k7"
			(at 0 0 90)
			(unlocked yes)
			(layer "B.Fab")
			(hide yes)
			(effects
				(font
					(size 1 1)
					(thickness 0.15)
				)
				(justify mirror)
			)
		)
		(property "License" "Apache-2.0"
			(at 0 0 90)
			(unlocked yes)
			(layer "B.Fab")
			(hide yes)
			(effects
				(font
					(size 1 1)
					(thickness 0.15)
				)
				(justify mirror)
			)
		)
		(property "Author" "Antmicro"
			(at 0 0 90)
			(unlocked yes)
			(layer "B.Fab")
			(hide yes)
			(effects
				(font
					(size 1 1)
					(thickness 0.15)
				)
				(justify mirror)
			)
		)
		(property "Tolerance" "1%"
			(at 0 0 90)
			(unlocked yes)
			(layer "B.Fab")
			(hide yes)
			(effects
				(font
					(size 1 1)
					(thickness 0.15)
				)
				(justify mirror)
			)
		)
		(sheetname "/USB Debug, PD/")
		(sheetfile "usb_debug_pd.kicad_sch")
		(attr smd exclude_from_pos_files exclude_from_bom dnp)
		(fp_poly
			(pts
				(xy -0.925 0.47) (xy 0.925 0.47) (xy 0.925 -0.47) (xy -0.925 -0.47)
			)
			(stroke
				(width 0.05)
				(type default)
			)
			(fill no)
			(layer "B.CrtYd")
		)
		(fp_poly
			(pts
				(xy -0.5 0.25) (xy 0.5 0.25) (xy 0.5 -0.25) (xy -0.5 -0.25)
			)
			(stroke
				(width 0.15)
				(type solid)
			)
			(fill no)
			(layer "B.Fab")
		)
		(fp_text user "${REFERENCE}"
			(at -0.95 -3.168 90)
			(layer "B.Fab")
			(effects
				(font
					(size 0.7 0.7)
					(thickness 0.15)
				)
				(justify left bottom mirror)
			)
		)
		(fp_text user "Author: Antmicro"
			(at -0.95 -4.169 90)
			(layer "B.Fab")
			(effects
				(font
					(size 0.7 0.7)
					(thickness 0.15)
				)
				(justify left bottom mirror)
			)
		)
		(fp_text user "License: Apache-2.0"
			(at -0.949999 -5.169 90)
			(layer "B.Fab")
			(effects
				(font
					(size 0.7 0.7)
					(thickness 0.15)
				)
				(justify left bottom mirror)
			)
		)
		(pad "1" smd roundrect
			(at -0.48 0 270)
			(size 0.59 0.64)
			(layers "B.Cu" "B.Mask" "B.Paste")
			(roundrect_rratio 0.25)
			(net 2 "+3V3")
			(pintype "passive")
		)
		(pad "2" smd roundrect
			(at 0.48 0 270)
			(size 0.59 0.64)
			(layers "B.Cu" "B.Mask" "B.Paste")
			(roundrect_rratio 0.25)
			(net 945 "/USB Debug, PD/DEBUG_SCL")
			(pintype "passive")
		)
	)
	(footprint "antmicro-footprints:R_0402_1005Metric"
		(layer "B.Cu")
		(at 227.4 95.4 -90)
		(descr "Resistor SMD 0402")
		(tags "resistor SMD 0402")
		(property "Reference" "R127"
			(at -1.225998 0.8 90)
			(layer "B.SilkS")
			(effects
				(font
					(size 0.7 0.7)
					(thickness 0.15)
				)
				(justify left bottom mirror)
			)
		)
		(property "Value" "R_10k_0402"
			(at -1.011843 -1.772046 90)
			(layer "B.Fab")
			(effects
				(font
					(size 0.7 0.7)
					(thickness 0.15)
				)
				(justify left bottom mirror)
			)
		)
		(property "Datasheet" "https://www.bourns.com/docs/product-datasheets/cr.pdf"
			(at 0 0 90)
			(layer "B.Fab")
			(hide yes)
			(effects
				(font
					(size 1.27 1.27)
					(thickness 0.15)
				)
				(justify mirror)
			)
		)
		(property "Description" "SMD Chip Resistor, 10 kohm, ± 1%, 62.5 mW, 0402 [1005 Metric], Thick Film, General Purpose"
			(at 0 0 90)
			(layer "B.Fab")
			(hide yes)
			(effects
				(font
					(size 1.27 1.27)
					(thickness 0.15)
				)
				(justify mirror)
			)
		)
		(property "Manufacturer" "Bourns"
			(at 0 0 90)
			(unlocked yes)
			(layer "B.Fab")
			(hide yes)
			(effects
				(font
					(size 1 1)
					(thickness 0.15)
				)
				(justify mirror)
			)
		)
		(property "MPN" "CR0402-FX-1002GLF"
			(at 0 0 90)
			(unlocked yes)
			(layer "B.Fab")
			(hide yes)
			(effects
				(font
					(size 1 1)
					(thickness 0.15)
				)
				(justify mirror)
			)
		)
		(property "Val" "10k"
			(at 0 0 90)
			(unlocked yes)
			(layer "B.Fab")
			(hide yes)
			(effects
				(font
					(size 1 1)
					(thickness 0.15)
				)
				(justify mirror)
			)
		)
		(property "License" "Apache-2.0"
			(at 0 0 90)
			(unlocked yes)
			(layer "B.Fab")
			(hide yes)
			(effects
				(font
					(size 1 1)
					(thickness 0.15)
				)
				(justify mirror)
			)
		)
		(property "Author" "Antmicro"
			(at 0 0 90)
			(unlocked yes)
			(layer "B.Fab")
			(hide yes)
			(effects
				(font
					(size 1 1)
					(thickness 0.15)
				)
				(justify mirror)
			)
		)
		(property "Tolerance" "1%"
			(at 0 0 90)
			(unlocked yes)
			(layer "B.Fab")
			(hide yes)
			(effects
				(font
					(size 1 1)
					(thickness 0.15)
				)
				(justify mirror)
			)
		)
		(sheetname "/USB DP Alt mode/")
		(sheetfile "usb_dp.kicad_sch")
		(attr smd)
		(fp_poly
			(pts
				(xy -0.925 0.47) (xy -0.925 -0.47) (xy 0.925 -0.47) (xy 0.925 0.47)
			)
			(stroke
				(width 0.05)
				(type default)
			)
			(fill no)
			(layer "B.CrtYd")
		)
		(fp_poly
			(pts
				(xy -0.5 0.25) (xy -0.5 -0.25) (xy 0.5 -0.25) (xy 0.5 0.25)
			)
			(stroke
				(width 0.15)
				(type solid)
			)
			(fill no)
			(layer "B.Fab")
		)
		(fp_text user "License: Apache-2.0"
			(at -0.949999 -5.169 90)
			(layer "B.Fab")
			(effects
				(font
					(size 0.7 0.7)
					(thickness 0.15)
				)
				(justify left bottom mirror)
			)
		)
		(fp_text user "Author: Antmicro"
			(at -0.95 -4.169 90)
			(layer "B.Fab")
			(effects
				(font
					(size 0.7 0.7)
					(thickness 0.15)
				)
				(justify left bottom mirror)
			)
		)
		(fp_text user "${REFERENCE}"
			(at -0.95 -3.168 90)
			(layer "B.Fab")
			(effects
				(font
					(size 0.7 0.7)
					(thickness 0.15)
				)
				(justify left bottom mirror)
			)
		)
		(pad "1" smd roundrect
			(at -0.48 0 270)
			(size 0.59 0.64)
			(layers "B.Cu" "B.Mask" "B.Paste")
			(roundrect_rratio 0.25)
			(net 962 "/SoM_IO/USBC1_FLG")
			(pintype "passive")
		)
		(pad "2" smd roundrect
			(at 0.48 0 270)
			(size 0.59 0.64)
			(layers "B.Cu" "B.Mask" "B.Paste")
			(roundrect_rratio 0.25)
			(net 2 "+3V3")
			(pintype "passive")
		)
	)
	(footprint "antmicro-footprints:C_0402_1005Metric"
		(layer "B.Cu")
		(at 205.9 79.2 180)
		(descr "Capacitor SMD 0402")
		(tags "capacitor SMD 0402")
		(property "Reference" "C118"
			(at -1.090532 -1.4 0)
			(layer "B.SilkS")
			(effects
				(font
					(size 0.7 0.7)
					(thickness 0.15)
				)
				(justify left bottom mirror)
			)
		)
		(property "Value" "C_10u_0402"
			(at -1.022927 -2.155213 0)
			(layer "B.Fab")
			(effects
				(font
					(size 0.7 0.7)
					(thickness 0.15)
				)
				(justify left bottom mirror)
			)
		)
		(property "Datasheet" "https://www.yageo.com/en/Chart/Download/pdf/CC0402MRX5R5BB106"
			(at 0 0 0)
			(layer "B.Fab")
			(hide yes)
			(effects
				(font
					(size 1.27 1.27)
					(thickness 0.15)
				)
				(justify mirror)
			)
		)
		(property "Description" "SMD Multilayer Ceramic Capacitor, 10 µF, 6.3 V, 0402 [1005 Metric], ± 20%, X5R, CC Series"
			(at 0 0 0)
			(layer "B.Fab")
			(hide yes)
			(effects
				(font
					(size 1.27 1.27)
					(thickness 0.15)
				)
				(justify mirror)
			)
		)
		(property "MPN" "CC0402MRX5R5BB106"
			(at 0 0 0)
			(unlocked yes)
			(layer "B.Fab")
			(hide yes)
			(effects
				(font
					(size 1 1)
					(thickness 0.15)
				)
				(justify mirror)
			)
		)
		(property "Manufacturer" "YAGEO"
			(at 0 0 0)
			(unlocked yes)
			(layer "B.Fab")
			(hide yes)
			(effects
				(font
					(size 1 1)
					(thickness 0.15)
				)
				(justify mirror)
			)
		)
		(property "License" "Apache-2.0"
			(at 0 0 0)
			(unlocked yes)
			(layer "B.Fab")
			(hide yes)
			(effects
				(font
					(size 1 1)
					(thickness 0.15)
				)
				(justify mirror)
			)
		)
		(property "Author" "Antmicro"
			(at 0 0 0)
			(unlocked yes)
			(layer "B.Fab")
			(hide yes)
			(effects
				(font
					(size 1 1)
					(thickness 0.15)
				)
				(justify mirror)
			)
		)
		(property "Val" "10u"
			(at 0 0 0)
			(unlocked yes)
			(layer "B.Fab")
			(hide yes)
			(effects
				(font
					(size 1 1)
					(thickness 0.15)
				)
				(justify mirror)
			)
		)
		(property "Voltage" ""
			(at 0 0 0)
			(unlocked yes)
			(layer "B.Fab")
			(hide yes)
			(effects
				(font
					(size 1 1)
					(thickness 0.15)
				)
				(justify mirror)
			)
		)
		(property "Dielectric" ""
			(at 0 0 0)
			(unlocked yes)
			(layer "B.Fab")
			(hide yes)
			(effects
				(font
					(size 1 1)
					(thickness 0.15)
				)
				(justify mirror)
			)
		)
		(sheetname "/USB Debug, PD/")
		(sheetfile "usb_debug_pd.kicad_sch")
		(attr smd)
		(fp_rect
			(start -0.925 0.47)
			(end 0.925 -0.47)
			(stroke
				(width 0.05)
				(type default)
			)
			(fill no)
			(layer "B.CrtYd")
		)
		(fp_line
			(start 0.504 0.25)
			(end 0.504 -0.248)
			(stroke
				(width 0.15)
				(type solid)
			)
			(layer "B.Fab")
		)
		(fp_line
			(start 0.504 -0.248)
			(end -0.494 -0.248)
			(stroke
				(width 0.15)
				(type solid)
			)
			(layer "B.Fab")
		)
		(fp_line
			(start -0.494 0.25)
			(end 0.504 0.25)
			(stroke
				(width 0.15)
				(type solid)
			)
			(layer "B.Fab")
		)
		(fp_line
			(start -0.494 -0.248)
			(end -0.494 0.25)
			(stroke
				(width 0.15)
				(type solid)
			)
			(layer "B.Fab")
		)
		(fp_text user "Author: Antmicro"
			(at -0.939 -3.399 0)
			(layer "B.Fab")
			(effects
				(font
					(size 0.7 0.7)
					(thickness 0.15)
				)
				(justify left bottom mirror)
			)
		)
		(fp_text user "${REFERENCE}"
			(at -0.939 -4.599 0)
			(layer "B.Fab")
			(effects
				(font
					(size 0.7 0.7)
					(thickness 0.15)
				)
				(justify left bottom mirror)
			)
		)
		(fp_text user "License: Apache-2.0"
			(at -0.939 -5.799 0)
			(layer "B.Fab")
			(effects
				(font
					(size 0.7 0.7)
					(thickness 0.15)
				)
				(justify left bottom mirror)
			)
		)
		(pad "1" smd roundrect
			(at -0.48 0 180)
			(size 0.59 0.64)
			(layers "B.Cu" "B.Mask" "B.Paste")
			(roundrect_rratio 0.25)
			(net 1 "GND")
			(pintype "passive")
		)
		(pad "2" smd roundrect
			(at 0.48 0 180)
			(size 0.59 0.64)
			(layers "B.Cu" "B.Mask" "B.Paste")
			(roundrect_rratio 0.25)
			(net 2 "+3V3")
			(pintype "passive")
		)
	)
	(footprint "antmicro-footprints:TP_SMD_0.75mm"
		(layer "B.Cu")
		(at 195.8 123.8 180)
		(property "Reference" "TP40"
			(at 3.4 0.4 180)
			(layer "B.SilkS")
			(effects
				(font
					(size 0.7 0.7)
					(thickness 0.15)
				)
				(justify right top mirror)
			)
		)
		(property "Value" "TP_0.75mm_SMD"
			(at 0 -1.2 180)
			(layer "B.Fab")
			(effects
				(font
					(size 0.7 0.7)
					(thickness 0.15)
				)
				(justify right top mirror)
			)
		)
		(property "Description" "SMT test point"
			(at 0 0 180)
			(layer "B.Fab")
			(hide yes)
			(effects
				(font
					(size 1.27 1.27)
					(thickness 0.15)
				)
				(justify mirror)
			)
		)
		(property "MPN" ""
			(at 0 0 0)
			(unlocked yes)
			(layer "B.Fab")
			(hide yes)
			(effects
				(font
					(size 1 1)
					(thickness 0.15)
				)
				(justify mirror)
			)
		)
		(property "Manufacturer" ""
			(at 0 0 0)
			(unlocked yes)
			(layer "B.Fab")
			(hide yes)
			(effects
				(font
					(size 1 1)
					(thickness 0.15)
				)
				(justify mirror)
			)
		)
		(property "Author" "Antmicro"
			(at 0 0 0)
			(unlocked yes)
			(layer "B.Fab")
			(hide yes)
			(effects
				(font
					(size 1 1)
					(thickness 0.15)
				)
				(justify mirror)
			)
		)
		(property "License" "Apache-2.0"
			(at 0 0 0)
			(unlocked yes)
			(layer "B.Fab")
			(hide yes)
			(effects
				(font
					(size 1 1)
					(thickness 0.15)
				)
				(justify mirror)
			)
		)
		(sheetname "/USB Hub/")
		(sheetfile "usb_hub.kicad_sch")
		(attr exclude_from_pos_files exclude_from_bom)
		(fp_circle
			(center 0 0)
			(end 0.475 0)
			(stroke
				(width 0.05)
				(type default)
			)
			(fill no)
			(layer "B.CrtYd")
		)
		(fp_text user "License: Apache-2.0"
			(at -0.4 -5.101 180)
			(layer "B.Fab")
			(effects
				(font
					(size 0.7 0.7)
					(thickness 0.15)
				)
				(justify right top mirror)
			)
		)
		(fp_text user "Author: Antmicro"
			(at -0.4 -3.901 180)
			(layer "B.Fab")
			(effects
				(font
					(size 0.7 0.7)
					(thickness 0.15)
				)
				(justify right top mirror)
			)
		)
		(fp_text user "${REFERENCE}"
			(at -0.4 -2.7 180)
			(layer "B.Fab")
			(effects
				(font
					(size 0.7 0.7)
					(thickness 0.15)
				)
				(justify right top mirror)
			)
		)
		(pad "1" smd circle
			(at 0 0 180)
			(size 0.75 0.75)
			(layers "B.Cu" "B.Mask")
			(net 912 "/USB Hub/PRT_CTL4")
			(pinfunction "1")
			(pintype "passive")
		)
	)
	(footprint "antmicro-footprints:SOT-523"
		(layer "B.Cu")
		(at 132.2 150.6 -90)
		(property "Reference" "Q1"
			(at -0.5 -5.19 90)
			(layer "B.SilkS")
			(effects
				(font
					(size 0.7 0.7)
					(thickness 0.15)
				)
				(justify left bottom mirror)
			)
		)
		(property "Value" "DMG1012T-7"
			(at 0.1 -1.824 90)
			(layer "B.Fab")
			(effects
				(font
					(size 0.7 0.7)
					(thickness 0.15)
				)
				(justify left bottom mirror)
			)
		)
		(property "Datasheet" "https://www.diodes.com/assets/Datasheets/ds31783.pdf"
			(at 0 0 90)
			(layer "B.Fab")
			(hide yes)
			(effects
				(font
					(size 1.27 1.27)
					(thickness 0.15)
				)
				(justify mirror)
			)
		)
		(property "Description" "Power MOSFET, N Channel, 20 V, 630 mA, 0.3 ohm, SOT-523, Surface Mount"
			(at 0 0 90)
			(layer "B.Fab")
			(hide yes)
			(effects
				(font
					(size 1.27 1.27)
					(thickness 0.15)
				)
				(justify mirror)
			)
		)
		(property "MPN" "DMG1012T-7"
			(at 0 0 90)
			(unlocked yes)
			(layer "B.Fab")
			(hide yes)
			(effects
				(font
					(size 1 1)
					(thickness 0.15)
				)
				(justify mirror)
			)
		)
		(property "Manufacturer" "Diodes Incorporated"
			(at 0 0 90)
			(unlocked yes)
			(layer "B.Fab")
			(hide yes)
			(effects
				(font
					(size 1 1)
					(thickness 0.15)
				)
				(justify mirror)
			)
		)
		(property "Author" "Antmicro"
			(at 0 0 90)
			(unlocked yes)
			(layer "B.Fab")
			(hide yes)
			(effects
				(font
					(size 1 1)
					(thickness 0.15)
				)
				(justify mirror)
			)
		)
		(property "License" "Apache-2.0"
			(at 0 0 90)
			(unlocked yes)
			(layer "B.Fab")
			(hide yes)
			(effects
				(font
					(size 1 1)
					(thickness 0.15)
				)
				(justify mirror)
			)
		)
		(sheetname "/Peripherals/")
		(sheetfile "peripherals.kicad_sch")
		(attr smd)
		(fp_line
			(start -0.725 0.551)
			(end -0.277 0.551)
			(stroke
				(width 0.15)
				(type solid)
			)
			(layer "B.SilkS")
		)
		(fp_line
			(start -0.277 0.551)
			(end -0.277 0.75)
			(stroke
				(width 0.15)
				(type solid)
			)
			(layer "B.SilkS")
		)
		(fp_line
			(start -0.927 0.351)
			(end -0.725 0.551)
			(stroke
				(width 0.15)
				(type solid)
			)
			(layer "B.SilkS")
		)
		(fp_line
			(start -0.927 0.051)
			(end -0.927 0.351)
			(stroke
				(width 0.15)
				(type solid)
			)
			(layer "B.SilkS")
		)
		(fp_circle
			(center -0.9652 -0.9652)
			(end -0.9152 -0.9652)
			(stroke
				(width 0.15)
				(type solid)
			)
			(fill yes)
			(layer "B.SilkS")
		)
		(fp_line
			(start -1.12 1.16)
			(end 1.1 1.16)
			(stroke
				(width 0.05)
				(type solid)
			)
			(layer "B.CrtYd")
		)
		(fp_line
			(start -1.12 1.16)
			(end -1.12 -1.15)
			(stroke
				(width 0.05)
				(type solid)
			)
			(layer "B.CrtYd")
		)
		(fp_line
			(start 1.1 1.16)
			(end 1.1 -1.15)
			(stroke
				(width 0.05)
				(type solid)
			)
			(layer "B.CrtYd")
		)
		(fp_line
			(start -1.12 -1.15)
			(end 1.1 -1.15)
			(stroke
				(width 0.05)
				(type solid)
			)
			(layer "B.CrtYd")
		)
		(fp_line
			(start -0.652 0.425)
			(end -0.802 0.276)
			(stroke
				(width 0.15)
				(type solid)
			)
			(layer "B.Fab")
		)
		(fp_line
			(start 0.8 0.425)
			(end -0.652 0.425)
			(stroke
				(width 0.15)
				(type solid)
			)
			(layer "B.Fab")
		)
		(fp_line
			(start 0.8 0.425)
			(end 0.8 -0.424)
			(stroke
				(width 0.15)
				(type solid)
			)
			(layer "B.Fab")
		)
		(fp_line
			(start -0.802 0.276)
			(end -0.802 -0.424)
			(stroke
				(width 0.15)
				(type solid)
			)
			(layer "B.Fab")
		)
		(fp_line
			(start 0.8 -0.424)
			(end -0.802 -0.424)
			(stroke
				(width 0.15)
				(type solid)
			)
			(layer "B.Fab")
		)
		(fp_circle
			(center -0.9652 -0.9652)
			(end -0.9144 -0.9652)
			(stroke
				(width 0.15)
				(type solid)
			)
			(fill no)
			(layer "B.Fab")
		)
		(fp_text user "${REFERENCE}"
			(at -1.12 -3.824 90)
			(layer "B.Fab")
			(effects
				(font
					(size 0.7 0.7)
					(thickness 0.15)
				)
				(justify left bottom mirror)
			)
		)
		(fp_text user "Author: Antmicro"
			(at -1.12 -6.224 90)
			(layer "B.Fab")
			(effects
				(font
					(size 0.7 0.7)
					(thickness 0.15)
				)
				(justify left bottom mirror)
			)
		)
		(fp_text user "License: Apache-2.0"
			(at -1.12 -5.024 90)
			(layer "B.Fab")
			(effects
				(font
					(size 0.7 0.7)
					(thickness 0.15)
				)
				(justify left bottom mirror)
			)
		)
		(pad "1" smd rect
			(at -0.5 -0.65 270)
			(size 0.4 0.51)
			(layers "B.Cu" "B.Mask" "B.Paste")
			(net 1100 "/Peripherals/TPM_RST")
			(pinfunction "G")
			(pintype "input")
		)
		(pad "2" smd rect
			(at 0.498 -0.65 270)
			(size 0.4 0.51)
			(layers "B.Cu" "B.Mask" "B.Paste")
			(net 1 "GND")
			(pinfunction "S")
			(pintype "passive")
		)
		(pad "3" smd rect
			(at 0 0.652 270)
			(size 0.4 0.51)
			(layers "B.Cu" "B.Mask" "B.Paste")
			(net 1089 "Net-(Q1-D)")
			(pinfunction "D")
			(pintype "passive")
		)
	)
)
